# BASEBOARD_FAB2 (Tioga Pass) — schematic netlist excerpt (pin names and nets, part order shuffled) for the footprints in the layout excerpt that follows; sources: Cadence DE-HDL packaged netlist, KiCad conversion of Wiwynn_Tioga_Pass_MB.brd

R8N4  RES  1.8K 1% CHIP  pkg 0402  page 55 : A = P3V3_STBY ; B = FM_CPU1_PROC_ID0
C2L39  CAP_A  0.01UF 25V 10% X7R  pkg 0402V  page 173 : A = SATA6G_P0_TX_C_DP ; B = SATA6G_PCH_PCIE_UP_SATA_TXP<0>
C9P15  CAP_A  0.1UF 16V 10% X7R  pkg 0402V  page 199 : A = A_HSC_ISET ; B = AGND_HSC

(kicad_pcb
	(version 20260206)
	(generator "pcbnew")
	(generator_version "10.0")
	(general
		(thickness 1.6)
		(legacy_teardrops no)
	)
	(paper "A4")
	(title_block
		(title "Wiwynn_Tioga_Pass_MB.brd")
		(comment 1 "Tioga Pass / footprints 3105-3107 of 4770")
	)
	(layers
		(0 "F.Cu" signal "TOP")
		(4 "In1.Cu" signal "L2GND")
		(6 "In2.Cu" signal "L3")
		(8 "In3.Cu" signal "L4GND")
		(10 "In4.Cu" signal "L5")
		(12 "In5.Cu" signal "L6GND")
		(14 "In6.Cu" signal "L7VCC")
		(16 "In7.Cu" signal "L8VCC")
		(18 "In8.Cu" signal "L9GND")
		(20 "In9.Cu" signal "L10")
		(22 "In10.Cu" signal "L11GND")
		(24 "In11.Cu" signal "L12")
		(26 "In12.Cu" signal "L13GND")
		(2 "B.Cu" signal "BOTTOM")
		(9 "F.Adhes" user "F.Adhesive")
		(11 "B.Adhes" user "B.Adhesive")
		(13 "F.Paste" user "Package Geometry/Pastemask Top")
		(15 "B.Paste" user "Package Geometry/Pastemask Bottom")
		(5 "F.SilkS" user "Ref Des/Silkscreen Top")
		(7 "B.SilkS" user "Ref Des/Silkscreen Bottom")
		(1 "F.Mask" user "Board Geometry/Soldermask Top")
		(3 "B.Mask" user "Board Geometry/Soldermask Bottom")
		(17 "Dwgs.User" user "User.Drawings")
		(19 "Cmts.User" user "User.Comments")
		(21 "Eco1.User" user "User.Eco1")
		(23 "Eco2.User" user "User.Eco2")
		(25 "Edge.Cuts" user "Board Geometry/Outline")
		(27 "Margin" user)
		(31 "F.CrtYd" user "Package Geometry/Place Bound Top")
		(29 "B.CrtYd" user "Package Geometry/Place Bound Bottom")
		(35 "F.Fab" user "Ref Des/Assembly Top")
		(33 "B.Fab" user "Ref Des/Assembly Bottom")
	)
	(footprint ""
		(layer "B.Cu")
		(at 63.2968 -89.9922 90)
		(property "Reference" "R8N4"
			(at 0 0 90)
			(layer "B.SilkS")
			(hide yes)
			(effects
				(font
					(size 1.27 1.27)
				)
				(justify mirror)
			)
		)
		(property "Value" ""
			(at 0 0 90)
			(layer "B.Fab")
			(effects
				(font
					(size 1.27 1.27)
				)
				(justify mirror)
			)
		)
		(duplicate_pad_numbers_are_jumpers no)
		(fp_poly
			(pts
				(xy 0.2794 -0.1016) (xy -0.2794 -0.1016) (xy -0.2794 0.9906) (xy 0.2794 0.9906)
			)
			(stroke
				(width 0)
				(type default)
			)
			(fill no)
			(layer "B.CrtYd")
		)
		(fp_line
			(start 0.2794 -0.1016)
			(end 0.2794 0.9906)
			(stroke
				(width 0.1)
				(type default)
			)
			(layer "B.Fab")
		)
		(fp_line
			(start -0.2794 -0.1016)
			(end 0.2794 -0.1016)
			(stroke
				(width 0.1)
				(type default)
			)
			(layer "B.Fab")
		)
		(fp_line
			(start 0.2794 0.9906)
			(end -0.2794 0.9906)
			(stroke
				(width 0.1)
				(type default)
			)
			(layer "B.Fab")
		)
		(fp_line
			(start -0.2794 0.9906)
			(end -0.2794 -0.1016)
			(stroke
				(width 0.1)
				(type default)
			)
			(layer "B.Fab")
		)
		(pad "1" smd rect
			(at 0 0 270)
			(size 0.508 0.508)
			(layers "B.Cu" "B.Mask" "B.Paste")
			(net "P3V3_STBY")
		)
		(pad "2" smd rect
			(at 0 0.889 270)
			(size 0.508 0.508)
			(layers "B.Cu" "B.Mask" "B.Paste")
			(net "FM_CPU1_PROC_ID0")
		)
		(zone
			(layer "B.Cu")
			(hatch none 0.5)
			(connect_pads
				(clearance 0)
			)
			(min_thickness 0.25)
			(keepout
				(tracks allowed)
				(vias not_allowed)
				(pads allowed)
				(copperpour not_allowed)
				(footprints allowed)
			)
			(placement
				(enabled no)
				(sheetname "")
			)
			(fill
				(thermal_gap 0.5)
				(thermal_bridge_width 0.5)
				(island_removal_mode 0)
			)
			(polygon
				(pts
					(xy 63.5508 -90.2462) (xy 63.5508 -89.7382) (xy 63.9318 -89.7382) (xy 63.9318 -90.2462)
				)
			)
		)
		(zone
			(layer "B.Cu")
			(hatch none 0.5)
			(connect_pads
				(clearance 0)
			)
			(min_thickness 0.25)
			(keepout
				(tracks not_allowed)
				(vias allowed)
				(pads allowed)
				(copperpour not_allowed)
				(footprints allowed)
			)
			(placement
				(enabled no)
				(sheetname "")
			)
			(fill
				(thermal_gap 0.5)
				(thermal_bridge_width 0.5)
				(island_removal_mode 0)
			)
			(polygon
				(pts
					(xy 63.9318 -90.2462) (xy 63.9318 -89.7382) (xy 63.5508 -89.7382) (xy 63.5508 -90.2462)
				)
			)
		)
	)
	(footprint ""
		(layer "B.Cu")
		(at 427.736 -142.0876)
		(property "Reference" "C2L39"
			(at 0 0 0)
			(layer "B.SilkS")
			(hide yes)
			(effects
				(font
					(size 1.27 1.27)
				)
				(justify mirror)
			)
		)
		(property "Value" ""
			(at 0 0 0)
			(layer "B.Fab")
			(effects
				(font
					(size 1.27 1.27)
				)
				(justify mirror)
			)
		)
		(duplicate_pad_numbers_are_jumpers no)
		(fp_poly
			(pts
				(xy -0.3048 -0.1016) (xy -0.3048 0.9906) (xy 0.3048 0.9906) (xy 0.3048 -0.1016)
			)
			(stroke
				(width 0)
				(type default)
			)
			(fill no)
			(layer "B.CrtYd")
		)
		(fp_line
			(start -0.3048 -0.1016)
			(end 0.3048 -0.1016)
			(stroke
				(width 0.1)
				(type default)
			)
			(layer "B.Fab")
		)
		(fp_line
			(start -0.3048 0.9906)
			(end -0.3048 -0.1016)
			(stroke
				(width 0.1)
				(type default)
			)
			(layer "B.Fab")
		)
		(fp_line
			(start 0.3048 -0.1016)
			(end 0.3048 0.9906)
			(stroke
				(width 0.1)
				(type default)
			)
			(layer "B.Fab")
		)
		(fp_line
			(start 0.3048 0.9906)
			(end -0.3048 0.9906)
			(stroke
				(width 0.1)
				(type default)
			)
			(layer "B.Fab")
		)
		(pad "1" smd rect
			(at 0 0 180)
			(size 0.508 0.508)
			(layers "B.Cu" "B.Mask" "B.Paste")
			(net "SATA6G_P0_TX_C_DP")
		)
		(pad "2" smd rect
			(at 0 0.889 180)
			(size 0.508 0.508)
			(layers "B.Cu" "B.Mask" "B.Paste")
			(net "SATA6G_PCH_PCIE_UP_SATA_TXP<0>")
		)
		(zone
			(layer "B.Cu")
			(hatch none 0.5)
			(connect_pads
				(clearance 0)
			)
			(min_thickness 0.25)
			(keepout
				(tracks allowed)
				(vias not_allowed)
				(pads allowed)
				(copperpour not_allowed)
				(footprints allowed)
			)
			(placement
				(enabled no)
				(sheetname "")
			)
			(fill
				(thermal_gap 0.5)
				(thermal_bridge_width 0.5)
				(island_removal_mode 0)
			)
			(polygon
				(pts
					(xy 427.99 -141.8336) (xy 427.482 -141.8336) (xy 427.482 -141.4526) (xy 427.99 -141.4526)
				)
			)
		)
		(zone
			(layer "B.Cu")
			(hatch none 0.5)
			(connect_pads
				(clearance 0)
			)
			(min_thickness 0.25)
			(keepout
				(tracks not_allowed)
				(vias allowed)
				(pads allowed)
				(copperpour not_allowed)
				(footprints allowed)
			)
			(placement
				(enabled no)
				(sheetname "")
			)
			(fill
				(thermal_gap 0.5)
				(thermal_bridge_width 0.5)
				(island_removal_mode 0)
			)
			(polygon
				(pts
					(xy 427.99 -141.4526) (xy 427.482 -141.4526) (xy 427.482 -141.8336) (xy 427.99 -141.8336)
				)
			)
		)
	)
	(footprint ""
		(layer "B.Cu")
		(at 22.57298 -74.42708 90)
		(property "Reference" "C9P15"
			(at 0 0 90)
			(layer "B.SilkS")
			(hide yes)
			(effects
				(font
					(size 1.27 1.27)
				)
				(justify mirror)
			)
		)
		(property "Value" ""
			(at 0 0 90)
			(layer "B.Fab")
			(effects
				(font
					(size 1.27 1.27)
				)
				(justify mirror)
			)
		)
		(duplicate_pad_numbers_are_jumpers no)
		(fp_poly
			(pts
				(xy -0.3048 -0.1016) (xy -0.3048 0.9906) (xy 0.3048 0.9906) (xy 0.3048 -0.1016)
			)
			(stroke
				(width 0)
				(type default)
			)
			(fill no)
			(layer "B.CrtYd")
		)
		(fp_line
			(start 0.3048 -0.1016)
			(end 0.3048 0.9906)
			(stroke
				(width 0.1)
				(type default)
			)
			(layer "B.Fab")
		)
		(fp_line
			(start -0.3048 -0.1016)
			(end 0.3048 -0.1016)
			(stroke
				(width 0.1)
				(type default)
			)
			(layer "B.Fab")
		)
		(fp_line
			(start 0.3048 0.9906)
			(end -0.3048 0.9906)
			(stroke
				(width 0.1)
				(type default)
			)
			(layer "B.Fab")
		)
		(fp_line
			(start -0.3048 0.9906)
			(end -0.3048 -0.1016)
			(stroke
				(width 0.1)
				(type default)
			)
			(layer "B.Fab")
		)
		(pad "1" smd rect
			(at 0 0 270)
			(size 0.508 0.508)
			(layers "B.Cu" "B.Mask" "B.Paste")
			(net "A_HSC_ISET")
		)
		(pad "2" smd rect
			(at 0 0.889 270)
			(size 0.508 0.508)
			(layers "B.Cu" "B.Mask" "B.Paste")
			(net "AGND_HSC")
		)
		(zone
			(layer "B.Cu")
			(hatch none 0.5)
			(connect_pads
				(clearance 0)
			)
			(min_thickness 0.25)
			(keepout
				(tracks allowed)
				(vias not_allowed)
				(pads allowed)
				(copperpour not_allowed)
				(footprints allowed)
			)
			(placement
				(enabled no)
				(sheetname "")
			)
			(fill
				(thermal_gap 0.5)
				(thermal_bridge_width 0.5)
				(island_removal_mode 0)
			)
			(polygon
				(pts
					(xy 22.82698 -74.68108) (xy 22.82698 -74.17308) (xy 23.20798 -74.17308) (xy 23.20798 -74.68108)
				)
			)
		)
		(zone
			(layer "B.Cu")
			(hatch none 0.5)
			(connect_pads
				(clearance 0)
			)
			(min_thickness 0.25)
			(keepout
				(tracks not_allowed)
				(vias allowed)
				(pads allowed)
				(copperpour not_allowed)
				(footprints allowed)
			)
			(placement
				(enabled no)
				(sheetname "")
			)
			(fill
				(thermal_gap 0.5)
				(thermal_bridge_width 0.5)
				(island_removal_mode 0)
			)
			(polygon
				(pts
					(xy 23.20798 -74.68108) (xy 23.20798 -74.17308) (xy 22.82698 -74.17308) (xy 22.82698 -74.68108)
				)
			)
		)
	)
)
